#ISCELL
  mstr_misc dns *
  *
#ISCELL
  pure_quanta quanta_title_block_c *
  *
#ISCELL
  pure_quanta_power universal_power *
  page364_i10
#ISCELL
  pure_quanta_power universal_gnd *
  page364_i12
#ISCELL
  pure_quanta_power universal_gnd *
  page364_i13
#CELL
  pure_quanta q_cap *
  page364_i14
#ISCELL
  pure_quanta_power universal_power *
  page364_i15
#ISCELL
  pure_quanta_power universal_gnd *
  page364_i22
#CELL
  pure_quanta q_res *
  page364_i24
#CELL
  pure_quanta q_res *
  page364_i25
#ISCELL
  pure_quanta_power universal_power *
  page364_i26
#ISCELL
  standard offpage *
  page364_i27
#CELL
  pure_quanta q_res *
  page364_i28
#CELL
  pure_quanta q_res *
  page364_i29
#CELL
  pure_quanta q_res *
  page364_i30
#CELL
  pure_quanta 74lvc1g08w57 *
  page364_i31
#CELL
  pure_quanta q_res *
  page364_i34
#ISCELL
  standard offpage *
  page364_i35
#ISCELL
  pure_quanta_power universal_gnd *
  page364_i36
#CELL
  pure_quanta 74lvc2g07dw7 *
  page364_i37
#ISCELL
  pure_quanta_power universal_power *
  page364_i38
#ISCELL
  pure_quanta_power universal_gnd *
  page364_i39
#CELL
  pure_quanta q_cap *
  page364_i40
#CELL
  pure_quanta q_res *
  page364_i41
#ISCELL
  standard offpage *
  page364_i42
#CELL
  pure_quanta q_res *
  page364_i43
#ISCELL
  pure_quanta_power universal_gnd *
  page364_i44
#ISCELL
  standard offpage *
  page364_i45
#ISCELL
  pure_quanta_power universal_power *
  page364_i46
#CELL
  pure_quanta q_res *
  page364_i47
#CELL
  pure_quanta q_res *
  page364_i48
#ISCELL
  standard offpage *
  page364_i49
#CELL
  pure_quanta q_res *
  page364_i50
#CELL
  pure_quanta q_res *
  page364_i51
#ISCELL
  pure_quanta_power universal_power *
  page364_i52
#CELL
  pure_quanta mosfet_nch_dual *
  page364_i53
#ISCELL
  pure_quanta_power universal_gnd *
  page364_i54
#CELL
  pure_quanta q_res *
  page364_i55
#ISCELL
  pure_quanta_power universal_power *
  page364_i56
#ISCELL
  pure_quanta_power universal_gnd *
  page364_i57
#CELL
  pure_quanta mosfet_nch_dual *
  page364_i58
#CELL
  pure_quanta q_res *
  page364_i59
#ISCELL
  pure_quanta_power universal_gnd *
  page364_i6
#ISCELL
  pure_quanta_power universal_power *
  page364_i60
#ISCELL
  pure_quanta_power universal_gnd *
  page364_i61
#CELL
  pure_quanta q_cap *
  page364_i62
#ISCELL
  standard offpage *
  page364_i63
#ISCELL
  pure_quanta_power universal_gnd *
  page364_i64
#ISCELL
  standard offpage *
  page364_i7
